# BASEBOARD_FAB2 (Tioga Pass) — schematic netlist excerpt (pin names and nets, part order shuffled) for the footprints in the layout excerpt that follows; sources: Cadence DE-HDL packaged netlist, KiCad conversion of Wiwynn_Tioga_Pass_MB.brd

J9L2  SCONN288_H44441003  SCONN  pkg PIP  page 86
  \12v\(1)  = P12V_NVDIMM_KLM
  VSS(93)  = GND
  DQ(4)  = M_L_DQ<4>
  VSS(92)  = GND
  DQ(0)  = M_L_DQ<0>
  VSS(91)  = GND
  DQS9P  = M_L_DQS_DP<9>
  DQS9N  = M_L_DQS_DN<9>
  VSS(90)  = GND
  DQ(6)  = M_L_DQ<6>
  VSS(89)  = GND
  DQ(2)  = M_L_DQ<2>
  VSS(88)  = GND
  DQ(12)  = M_L_DQ<12>
  VSS(87)  = GND
  DQ(8)  = M_L_DQ<8>
  VSS(86)  = GND
  DQS10P  = M_L_DQS_DP<10>
  DQS10N  = M_L_DQS_DN<10>
  VSS(85)  = GND
  DQ(14)  = M_L_DQ<14>
  VSS(84)  = GND
  DQ(10)  = M_L_DQ<10>
  VSS(83)  = GND
  DQ(20)  = M_L_DQ<20>
  VSS(82)  = GND
  DQ(16)  = M_L_DQ<16>
  VSS(81)  = GND
  DQS11P  = M_L_DQS_DP<11>
  DQS11N  = M_L_DQS_DN<11>
  VSS(80)  = GND
  DQ(22)  = M_L_DQ<22>
  VSS(79)  = GND
  DQ(18)  = M_L_DQ<18>
  VSS(78)  = GND
  DQ(28)  = M_L_DQ<28>
  VSS(77)  = GND
  DQ(24)  = M_L_DQ<24>
  VSS(76)  = GND
  DQS12P  = M_L_DQS_DP<12>
  DQS12N  = M_L_DQS_DN<12>
  VSS(75)  = GND
  DQ(30)  = M_L_DQ<30>
  VSS(74)  = GND
  DQ(26)  = M_L_DQ<26>
  VSS(73)  = GND
  CB(4)  = M_L_ECC<4>
  VSS(72)  = GND
  CB(0)  = M_L_ECC<0>
  VSS(71)  = GND
  DQS17P  = M_L_DQS_DP<17>
  DQS17N  = M_L_DQS_DN<17>
  VSS(70)  = GND
  CB(6)  = M_L_ECC<6>
  VSS(69)  = GND
  CB(2)  = M_L_ECC<2>
  VSS(68)  = GND
  RESET_N  = M_KLM_RST_N
  VDD(25)  = PVDDQ_KLM
  CKE(0)  = M_L_CKE<2>
  VDD(24)  = PVDDQ_KLM
  ACT_N  = M_L_ACT_N
  BG(0)  = M_L_BG<0>
  VDD(23)  = PVDDQ_KLM
  A12  = M_L_MA<12>
  A9  = M_L_MA<9>
  VDD(22)  = PVDDQ_KLM
  A8  = M_L_MA<8>
  A6  = M_L_MA<6>
  VDD(21)  = PVDDQ_KLM
  A3  = M_L_MA<3>
  A1  = M_L_MA<1>
  VDD(20)  = PVDDQ_KLM
  CK0P  = M_L_CLK_DP<2>
  CK0N  = M_L_CLK_DN<2>
  VDD(19)  = PVDDQ_KLM
  VTT(1)  = PVTT_KLM
  EVENT_N  = FM_DIMM_EVENT_COD_N
  A0  = M_L_MA<0>
  VDD(18)  = PVDDQ_KLM
  BA(0)  = M_L_BA<0>
  A16_RAS_N  = M_L_MA<16>
  VDD(17)  = PVDDQ_KLM
  S0_N  = M_L_CS_N<4>
  VDD(16)  = PVDDQ_KLM
  A15_CAS_N  = M_L_MA<15>
  ODT(0)  = M_L_ODT<2>
  VDD(15)  = PVDDQ_KLM
  S1_N  = M_L_CS_N<5>
  VDD(14)  = PVDDQ_KLM
  ODT(1)  = M_L_ODT<3>
  VDD(13)  = PVDDQ_KLM
  S2_N_C(0)  = M_L_CS_N<6>
  VSS(67)  = GND
  DQ(36)  = M_L_DQ<36>
  VSS(66)  = GND
  DQ(32)  = M_L_DQ<32>
  VSS(65)  = GND
  DQS13P  = M_L_DQS_DP<13>
  DQS13N  = M_L_DQS_DN<13>
  VSS(64)  = GND
  DQ(38)  = M_L_DQ<38>
  VSS(63)  = GND
  DQ(34)  = M_L_DQ<34>
  VSS(62)  = GND
  DQ(44)  = M_L_DQ<44>
  VSS(61)  = GND
  DQ(40)  = M_L_DQ<40>
  VSS(60)  = GND
  DQS14P  = M_L_DQS_DP<14>
  DQS14N  = M_L_DQS_DN<14>
  VSS(59)  = GND
  DQ(46)  = M_L_DQ<46>
  VSS(58)  = GND
  DQ(42)  = M_L_DQ<42>
  VSS(57)  = GND
  DQ(52)  = M_L_DQ<52>
  VSS(56)  = GND
  DQ(48)  = M_L_DQ<48>
  VSS(55)  = GND
  DQS15P  = M_L_DQS_DP<15>
  DQS15N  = M_L_DQS_DN<15>
  VSS(54)  = GND
  DQ(54)  = M_L_DQ<54>
  VSS(53)  = GND
  DQ(50)  = M_L_DQ<50>
  VSS(52)  = GND
  DQ(60)  = M_L_DQ<60>
  VSS(51)  = GND
  DQ(56)  = M_L_DQ<56>
  VSS(50)  = GND
  DQS16P  = M_L_DQS_DP<16>
  DQS16N  = M_L_DQS_DN<16>
  VSS(49)  = GND
  DQ(62)  = M_L_DQ<62>
  VSS(48)  = GND
  DQ(58)  = M_L_DQ<58>
  VSS(47)  = GND
  SA(0)  = PVPP_KLM
  SA(1)  = PVPP_KLM
  SCL  = SMB_DDR_KLM_VPP_SCL
  VPP(4)  = PVPP_KLM
  VPP(3)  = PVPP_KLM
  RFU(2)  = TP_CH_L_DIMM0_RFU_2
  \12v\(0)  = P12V_NVDIMM_KLM
  VREFCA  = M_L_VREF
  VSS(46)  = GND
  DQ(5)  = M_L_DQ<5>
  VSS(45)  = GND
  DQ(1)  = M_L_DQ<1>
  VSS(44)  = GND
  DQS0N  = M_L_DQS_DN<0>
  DQS0P  = M_L_DQS_DP<0>
  VSS(43)  = GND
  DQ(7)  = M_L_DQ<7>
  VSS(42)  = GND
  DQ(3)  = M_L_DQ<3>
  VSS(41)  = GND
  DQ(13)  = M_L_DQ<13>
  VSS(40)  = GND
  DQ(9)  = M_L_DQ<9>
  VSS(39)  = GND
  DQS1N  = M_L_DQS_DN<1>
  DQS1P  = M_L_DQS_DP<1>
  VSS(38)  = GND
  DQ(15)  = M_L_DQ<15>
  VSS(37)  = GND
  DQ(11)  = M_L_DQ<11>
  VSS(36)  = GND
  DQ(21)  = M_L_DQ<21>
  VSS(35)  = GND
  DQ(17)  = M_L_DQ<17>
  VSS(34)  = GND
  DQS2N  = M_L_DQS_DN<2>
  DQS2P  = M_L_DQS_DP<2>
  VSS(33)  = GND
  DQ(23)  = M_L_DQ<23>
  VSS(32)  = GND
  DQ(19)  = M_L_DQ<19>
  VSS(31)  = GND
  DQ(29)  = M_L_DQ<29>
  VSS(30)  = GND
  DQ(25)  = M_L_DQ<25>
  VSS(29)  = GND
  DQS3N  = M_L_DQS_DN<3>
  DQS3P  = M_L_DQS_DP<3>
  VSS(28)  = GND
  DQ(31)  = M_L_DQ<31>
  VSS(27)  = GND
  DQ(27)  = M_L_DQ<27>
  VSS(26)  = GND
  CB(5)  = M_L_ECC<5>
  VSS(25)  = GND
  CB(1)  = M_L_ECC<1>
  VSS(24)  = GND
  DQS8N  = M_L_DQS_DN<8>
  DQS8P  = M_L_DQS_DP<8>
  VSS(23)  = GND
  CB(7)  = M_L_ECC<7>
  VSS(22)  = GND
  CB(3)  = M_L_ECC<3>
  VSS(21)  = GND
  CKE(1)  = M_L_CKE<3>
  VDD(12)  = PVDDQ_KLM
  RFU(0)  = TP_CH_L_DIMM0_RFU_0
  VDD(11)  = PVDDQ_KLM
  BG(1)  = M_L_BG<1>
  ALERT_N  = M_L_ALERT_N
  VDD(10)  = PVDDQ_KLM
  A11  = M_L_MA<11>
  A7  = M_L_MA<7>
  VDD(9)  = PVDDQ_KLM
  A5  = M_L_MA<5>
  A4  = M_L_MA<4>
  VDD(8)  = PVDDQ_KLM
  A2  = M_L_MA<2>
  VDD(7)  = PVDDQ_KLM
  CK1P  = M_L_CLK_DP<3>
  CK1N  = M_L_CLK_DN<3>
  VDD(6)  = PVDDQ_KLM
  VTT(0)  = PVTT_KLM
  PAR  = M_L_PAR
  VDD(5)  = PVDDQ_KLM
  BA(1)  = M_L_BA<1>
  A10  = M_L_MA<10>
  VDD(4)  = PVDDQ_KLM
  RFU(1)  = TP_CH_L_DIMM0_RFU_1
  A14_WE_N  = M_L_MA<14>
  VDD(3)  = PVDDQ_KLM
  SAVE_N_NC  = FM_ADR_COMPLETE_KLM_N
  VDD(2)  = PVDDQ_KLM
  A13  = M_L_MA<13>
  VDD(1)  = PVDDQ_KLM
  A17  = M_L_MA<17>
  C(2)  = M_L_C<2>
  VDD(0)  = PVDDQ_KLM
  S3_N_C(1)  = M_L_CS_N<7>
  SA(2)  = GND
  VSS(20)  = GND
  DQ(37)  = M_L_DQ<37>
  VSS(19)  = GND
  DQ(33)  = M_L_DQ<33>
  VSS(18)  = GND
  DQS4N  = M_L_DQS_DN<4>
  DQS4P  = M_L_DQS_DP<4>
  VSS(17)  = GND
  DQ(39)  = M_L_DQ<39>
  VSS(16)  = GND
  DQ(35)  = M_L_DQ<35>
  VSS(15)  = GND
  DQ(45)  = M_L_DQ<45>
  VSS(14)  = GND
  DQ(41)  = M_L_DQ<41>
  VSS(13)  = GND
  DQS5N  = M_L_DQS_DN<5>
  DQS5P  = M_L_DQS_DP<5>
  VSS(12)  = GND
  DQ(47)  = M_L_DQ<47>
  VSS(11)  = GND
  DQ(43)  = M_L_DQ<43>
  VSS(10)  = GND
  DQ(53)  = M_L_DQ<53>
  VSS(9)  = GND
  DQ(49)  = M_L_DQ<49>
  VSS(8)  = GND
  DQS6N  = M_L_DQS_DN<6>
  DQS6P  = M_L_DQS_DP<6>
  VSS(7)  = GND
  DQ(55)  = M_L_DQ<55>
  VSS(6)  = GND
  DQ(51)  = M_L_DQ<51>
  VSS(5)  = GND
  DQ(61)  = M_L_DQ<61>
  VSS(4)  = GND
  DQ(57)  = M_L_DQ<57>
  VSS(3)  = GND
  DQS7N  = M_L_DQS_DN<7>
  DQS7P  = M_L_DQS_DP<7>
  VSS(2)  = GND
  DQ(63)  = M_L_DQ<63>
  VSS(1)  = GND
  DQ(59)  = M_L_DQ<59>
  VSS(0)  = GND
  VDDSPD  = PVPP_KLM
  SDA  = SMB_DDR_KLM_VPP_SDA
  VPP(1)  = PVPP_KLM
  VPP(0)  = PVPP_KLM
  VPP(2)  = PVPP_KLM

(kicad_pcb
	(version 20260206)
	(generator "pcbnew")
	(generator_version "10.0")
	(general
		(thickness 1.6)
		(legacy_teardrops no)
	)
	(paper "A4")
	(title_block
		(title "Wiwynn_Tioga_Pass_MB.brd")
		(comment 1 "Tioga Pass / footprint 4281 of 4770 (J9L2), pads 51-100 of 291")
	)
	(layers
		(0 "F.Cu" signal "TOP")
		(4 "In1.Cu" signal "L2GND")
		(6 "In2.Cu" signal "L3")
		(8 "In3.Cu" signal "L4GND")
		(10 "In4.Cu" signal "L5")
		(12 "In5.Cu" signal "L6GND")
		(14 "In6.Cu" signal "L7VCC")
		(16 "In7.Cu" signal "L8VCC")
		(18 "In8.Cu" signal "L9GND")
		(20 "In9.Cu" signal "L10")
		(22 "In10.Cu" signal "L11GND")
		(24 "In11.Cu" signal "L12")
		(26 "In12.Cu" signal "L13GND")
		(2 "B.Cu" signal "BOTTOM")
		(9 "F.Adhes" user "F.Adhesive")
		(11 "B.Adhes" user "B.Adhesive")
		(13 "F.Paste" user "Package Geometry/Pastemask Top")
		(15 "B.Paste" user "Package Geometry/Pastemask Bottom")
		(5 "F.SilkS" user "Ref Des/Silkscreen Top")
		(7 "B.SilkS" user "Ref Des/Silkscreen Bottom")
		(1 "F.Mask" user "Board Geometry/Soldermask Top")
		(3 "B.Mask" user "Board Geometry/Soldermask Bottom")
		(17 "Dwgs.User" user "User.Drawings")
		(19 "Cmts.User" user "User.Comments")
		(21 "Eco1.User" user "User.Eco1")
		(23 "Eco2.User" user "User.Eco2")
		(25 "Edge.Cuts" user "Board Geometry/Outline")
		(27 "Margin" user)
		(31 "F.CrtYd" user "Package Geometry/Place Bound Top")
		(29 "B.CrtYd" user "Package Geometry/Place Bound Bottom")
		(35 "F.Fab" user "Ref Des/Assembly Top")
		(33 "B.Fab" user "Ref Des/Assembly Bottom")
	)
	(footprint ""
		(layer "B.Cu")
		(at 29.699458 -142.477236 90)
		(property "Reference" "J9L2"
			(at 2.403348 38.118542 0)
			(unlocked yes)
			(layer "B.SilkS")
			(effects
				(font
					(size 0.7874 0.5842)
					(thickness 0.1524)
				)
				(justify left mirror)
			)
		)
		(property "Value" ""
			(at 0 0 90)
			(layer "B.Fab")
			(effects
				(font
					(size 1.27 1.27)
				)
				(justify mirror)
			)
		)
		(duplicate_pad_numbers_are_jumpers no)
		(pad "48" smd rect
			(at 0 39.949882 270)
			(size 1.8034 0.508)
			(layers "B.Cu" "B.Mask" "B.Paste")
			(net "GND")
		)
		(pad "49" smd rect
			(at 0 40.80002 270)
			(size 1.8034 0.508)
			(layers "B.Cu" "B.Mask" "B.Paste")
			(net "M_L_ECC<0>")
		)
		(pad "50" smd rect
			(at 0 41.649904 270)
			(size 1.8034 0.508)
			(layers "B.Cu" "B.Mask" "B.Paste")
			(net "GND")
		)
		(pad "51" smd rect
			(at 0 42.500042 270)
			(size 1.8034 0.508)
			(layers "B.Cu" "B.Mask" "B.Paste")
			(net "M_L_DQS_DP<17>")
		)
		(pad "52" smd rect
			(at 0 43.349926 270)
			(size 1.8034 0.508)
			(layers "B.Cu" "B.Mask" "B.Paste")
			(net "M_L_DQS_DN<17>")
		)
		(pad "53" smd rect
			(at 0 44.200064 270)
			(size 1.8034 0.508)
			(layers "B.Cu" "B.Mask" "B.Paste")
			(net "GND")
		)
		(pad "54" smd rect
			(at 0 45.049948 270)
			(size 1.8034 0.508)
			(layers "B.Cu" "B.Mask" "B.Paste")
			(net "M_L_ECC<6>")
		)
		(pad "55" smd rect
			(at 0 45.900086 270)
			(size 1.8034 0.508)
			(layers "B.Cu" "B.Mask" "B.Paste")
			(net "GND")
		)
		(pad "56" smd rect
			(at 0 46.74997 270)
			(size 1.8034 0.508)
			(layers "B.Cu" "B.Mask" "B.Paste")
			(net "M_L_ECC<2>")
		)
		(pad "57" smd rect
			(at 0 47.600108 270)
			(size 1.8034 0.508)
			(layers "B.Cu" "B.Mask" "B.Paste")
			(net "GND")
		)
		(pad "58" smd rect
			(at 0 48.449992 270)
			(size 1.8034 0.508)
			(layers "B.Cu" "B.Mask" "B.Paste")
			(net "M_KLM_RST_N")
		)
		(pad "59" smd rect
			(at 0 49.299876 270)
			(size 1.8034 0.508)
			(layers "B.Cu" "B.Mask" "B.Paste")
			(net "PVDDQ_KLM")
		)
		(pad "60" smd rect
			(at 0 50.150014 270)
			(size 1.8034 0.508)
			(layers "B.Cu" "B.Mask" "B.Paste")
			(net "M_L_CKE<2>")
		)
		(pad "61" smd rect
			(at 0 50.999898 270)
			(size 1.8034 0.508)
			(layers "B.Cu" "B.Mask" "B.Paste")
			(net "PVDDQ_KLM")
		)
		(pad "62" smd rect
			(at 0 51.850036 270)
			(size 1.8034 0.508)
			(layers "B.Cu" "B.Mask" "B.Paste")
			(net "M_L_ACT_N")
		)
		(pad "63" smd rect
			(at 0 52.69992 270)
			(size 1.8034 0.508)
			(layers "B.Cu" "B.Mask" "B.Paste")
			(net "M_L_BG<0>")
		)
		(pad "64" smd rect
			(at 0 53.550058 270)
			(size 1.8034 0.508)
			(layers "B.Cu" "B.Mask" "B.Paste")
			(net "PVDDQ_KLM")
		)
		(pad "65" smd rect
			(at 0 54.399942 270)
			(size 1.8034 0.508)
			(layers "B.Cu" "B.Mask" "B.Paste")
			(net "M_L_MA<12>")
		)
		(pad "66" smd rect
			(at 0 55.25008 270)
			(size 1.8034 0.508)
			(layers "B.Cu" "B.Mask" "B.Paste")
			(net "M_L_MA<9>")
		)
		(pad "67" smd rect
			(at 0 56.099964 270)
			(size 1.8034 0.508)
			(layers "B.Cu" "B.Mask" "B.Paste")
			(net "PVDDQ_KLM")
		)
		(pad "68" smd rect
			(at 0 56.950102 270)
			(size 1.8034 0.508)
			(layers "B.Cu" "B.Mask" "B.Paste")
			(net "M_L_MA<8>")
		)
		(pad "69" smd rect
			(at 0 57.799986 270)
			(size 1.8034 0.508)
			(layers "B.Cu" "B.Mask" "B.Paste")
			(net "M_L_MA<6>")
		)
		(pad "70" smd rect
			(at 0 58.650124 270)
			(size 1.8034 0.508)
			(layers "B.Cu" "B.Mask" "B.Paste")
			(net "PVDDQ_KLM")
		)
		(pad "71" smd rect
			(at 0 59.500008 270)
			(size 1.8034 0.508)
			(layers "B.Cu" "B.Mask" "B.Paste")
			(net "M_L_MA<3>")
		)
		(pad "72" smd rect
			(at 0 60.349892 270)
			(size 1.8034 0.508)
			(layers "B.Cu" "B.Mask" "B.Paste")
			(net "M_L_MA<1>")
		)
		(pad "73" smd rect
			(at 0 61.20003 270)
			(size 1.8034 0.508)
			(layers "B.Cu" "B.Mask" "B.Paste")
			(net "PVDDQ_KLM")
		)
		(pad "74" smd rect
			(at 0 62.049914 270)
			(size 1.8034 0.508)
			(layers "B.Cu" "B.Mask" "B.Paste")
			(net "M_L_CLK_DP<2>")
		)
		(pad "75" smd rect
			(at 0 62.900052 270)
			(size 1.8034 0.508)
			(layers "B.Cu" "B.Mask" "B.Paste")
			(net "M_L_CLK_DN<2>")
		)
		(pad "76" smd rect
			(at 0 63.749936 270)
			(size 1.8034 0.508)
			(layers "B.Cu" "B.Mask" "B.Paste")
			(net "PVDDQ_KLM")
		)
		(pad "77" smd rect
			(at 0 64.600074 270)
			(size 1.8034 0.508)
			(layers "B.Cu" "B.Mask" "B.Paste")
			(net "PVTT_KLM")
		)
		(pad "78" smd rect
			(at 0 70.550024 270)
			(size 1.8034 0.508)
			(layers "B.Cu" "B.Mask" "B.Paste")
			(net "FM_DIMM_EVENT_COD_N")
		)
		(pad "79" smd rect
			(at 0 71.399908 270)
			(size 1.8034 0.508)
			(layers "B.Cu" "B.Mask" "B.Paste")
			(net "M_L_MA<0>")
		)
		(pad "80" smd rect
			(at 0 72.250046 270)
			(size 1.8034 0.508)
			(layers "B.Cu" "B.Mask" "B.Paste")
			(net "PVDDQ_KLM")
		)
		(pad "81" smd rect
			(at 0 73.09993 270)
			(size 1.8034 0.508)
			(layers "B.Cu" "B.Mask" "B.Paste")
			(net "M_L_BA<0>")
		)
		(pad "82" smd rect
			(at 0 73.950068 270)
			(size 1.8034 0.508)
			(layers "B.Cu" "B.Mask" "B.Paste")
			(net "M_L_MA<16>")
		)
		(pad "83" smd rect
			(at 0 74.799952 270)
			(size 1.8034 0.508)
			(layers "B.Cu" "B.Mask" "B.Paste")
			(net "PVDDQ_KLM")
		)
		(pad "84" smd rect
			(at 0 75.65009 270)
			(size 1.8034 0.508)
			(layers "B.Cu" "B.Mask" "B.Paste")
			(net "M_L_CS_N<4>")
		)
		(pad "85" smd rect
			(at 0 76.499974 270)
			(size 1.8034 0.508)
			(layers "B.Cu" "B.Mask" "B.Paste")
			(net "PVDDQ_KLM")
		)
		(pad "86" smd rect
			(at 0 77.350112 270)
			(size 1.8034 0.508)
			(layers "B.Cu" "B.Mask" "B.Paste")
			(net "M_L_MA<15>")
		)
		(pad "87" smd rect
			(at 0 78.199996 270)
			(size 1.8034 0.508)
			(layers "B.Cu" "B.Mask" "B.Paste")
			(net "M_L_ODT<2>")
		)
		(pad "88" smd rect
			(at 0 79.04988 270)
			(size 1.8034 0.508)
			(layers "B.Cu" "B.Mask" "B.Paste")
			(net "PVDDQ_KLM")
		)
		(pad "89" smd rect
			(at 0 79.900018 270)
			(size 1.8034 0.508)
			(layers "B.Cu" "B.Mask" "B.Paste")
			(net "M_L_CS_N<5>")
		)
		(pad "90" smd rect
			(at 0 80.749902 270)
			(size 1.8034 0.508)
			(layers "B.Cu" "B.Mask" "B.Paste")
			(net "PVDDQ_KLM")
		)
		(pad "91" smd rect
			(at 0 81.60004 270)
			(size 1.8034 0.508)
			(layers "B.Cu" "B.Mask" "B.Paste")
			(net "M_L_ODT<3>")
		)
		(pad "92" smd rect
			(at 0 82.449924 270)
			(size 1.8034 0.508)
			(layers "B.Cu" "B.Mask" "B.Paste")
			(net "PVDDQ_KLM")
		)
		(pad "93" smd rect
			(at 0 83.300062 270)
			(size 1.8034 0.508)
			(layers "B.Cu" "B.Mask" "B.Paste")
			(net "M_L_CS_N<6>")
		)
		(pad "94" smd rect
			(at 0 84.149946 270)
			(size 1.8034 0.508)
			(layers "B.Cu" "B.Mask" "B.Paste")
			(net "GND")
		)
		(pad "95" smd rect
			(at 0 85.000084 270)
			(size 1.8034 0.508)
			(layers "B.Cu" "B.Mask" "B.Paste")
			(net "M_L_DQ<36>")
		)
		(pad "96" smd rect
			(at 0 85.849968 270)
			(size 1.8034 0.508)
			(layers "B.Cu" "B.Mask" "B.Paste")
			(net "GND")
		)
		(pad "97" smd rect
			(at 0 86.700106 270)
			(size 1.8034 0.508)
			(layers "B.Cu" "B.Mask" "B.Paste")
			(net "M_L_DQ<32>")
		)
	)
)
